(kicad_pcb
	(version 20260206)
	(generator "pcbnew")
	(generator_version "10.0")
	(general
		(thickness 1.6)
		(legacy_teardrops no)
	)
	(paper "A4")
	(title_block
		(title "04192023_DAF0TMB3IC0_F0TG_MB_C_brd_V02_OCP.brd")
		(comment 1 "Grand Teton / footprints 2791-2797 of 8354")
	)
	(layers
		(0 "F.Cu" signal "TOP")
		(4 "In1.Cu" signal "GND")
		(6 "In2.Cu" signal "IN1")
		(8 "In3.Cu" signal "GND1")
		(10 "In4.Cu" signal "IN2")
		(12 "In5.Cu" signal "GND2")
		(14 "In6.Cu" signal "IN3")
		(16 "In7.Cu" signal "GND3")
		(18 "In8.Cu" signal "VCC")
		(20 "In9.Cu" signal "VCC1")
		(22 "In10.Cu" signal "GND4")
		(24 "In11.Cu" signal "IN4")
		(26 "In12.Cu" signal "GND5")
		(28 "In13.Cu" signal "IN5")
		(30 "In14.Cu" signal "GND6")
		(32 "In15.Cu" signal "IN6")
		(34 "In16.Cu" signal "GND7")
		(2 "B.Cu" signal "BOTTOM")
		(9 "F.Adhes" user "F.Adhesive")
		(11 "B.Adhes" user "B.Adhesive")
		(13 "F.Paste" user "Package Geometry/Pastemask Top")
		(15 "B.Paste" user "Package Geometry/Pastemask Bottom")
		(5 "F.SilkS" user "Ref Des/Silkscreen Top")
		(7 "B.SilkS" user "Ref Des/Silkscreen Bottom")
		(1 "F.Mask" user "Board Geometry/Soldermask Top")
		(3 "B.Mask" user "Board Geometry/Soldermask Bottom")
		(17 "Dwgs.User" user "User.Drawings")
		(19 "Cmts.User" user "User.Comments")
		(21 "Eco1.User" user "User.Eco1")
		(23 "Eco2.User" user "User.Eco2")
		(25 "Edge.Cuts" user "Board Geometry/Outline")
		(27 "Margin" user)
		(31 "F.CrtYd" user "Package Geometry/Place Bound Top")
		(29 "B.CrtYd" user "Package Geometry/Place Bound Bottom")
		(35 "F.Fab" user "Ref Des/Assembly Top")
		(33 "B.Fab" user "Ref Des/Assembly Bottom")
	)
	(footprint ""
		(layer "F.Cu")
		(at 317.246 -364.617 90)
		(property "Reference" "PC75"
			(at 0 0 90)
			(layer "F.SilkS")
			(hide yes)
			(effects
				(font
					(size 1.27 1.27)
				)
			)
		)
		(property "Value" ""
			(at 0 0 90)
			(layer "F.Fab")
			(effects
				(font
					(size 1.27 1.27)
				)
			)
		)
		(duplicate_pad_numbers_are_jumpers no)
		(fp_line
			(start 0.7874 -0.4064)
			(end 0.7874 0.4064)
			(stroke
				(width 0.1524)
				(type default)
			)
			(layer "F.SilkS")
		)
		(fp_line
			(start -0.7874 -0.4064)
			(end 0.7874 -0.4064)
			(stroke
				(width 0.1524)
				(type default)
			)
			(layer "F.SilkS")
		)
		(fp_line
			(start 0.7874 0.4064)
			(end -0.7874 0.4064)
			(stroke
				(width 0.1524)
				(type default)
			)
			(layer "F.SilkS")
		)
		(fp_line
			(start -0.7874 0.4064)
			(end -0.7874 -0.4064)
			(stroke
				(width 0.1524)
				(type default)
			)
			(layer "F.SilkS")
		)
		(fp_line
			(start -0.12065 -0.305054)
			(end -0.12065 -0.2794)
			(stroke
				(width 0.1)
				(type default)
			)
			(layer "F.Fab")
		)
		(fp_line
			(start -0.67945 -0.305054)
			(end -0.12065 -0.305054)
			(stroke
				(width 0.1)
				(type default)
			)
			(layer "F.Fab")
		)
		(fp_line
			(start 0.67945 -0.3048)
			(end 0.67945 0.3048)
			(stroke
				(width 0.1)
				(type default)
			)
			(layer "F.Fab")
		)
		(fp_line
			(start 0.12065 -0.3048)
			(end 0.67945 -0.3048)
			(stroke
				(width 0.1)
				(type default)
			)
			(layer "F.Fab")
		)
		(fp_line
			(start 0.12065 -0.2794)
			(end 0.12065 -0.3048)
			(stroke
				(width 0.1)
				(type default)
			)
			(layer "F.Fab")
		)
		(fp_line
			(start -0.12065 -0.2794)
			(end 0.12065 -0.2794)
			(stroke
				(width 0.1)
				(type default)
			)
			(layer "F.Fab")
		)
		(fp_line
			(start 0.120396 0.2794)
			(end -0.12065 0.2794)
			(stroke
				(width 0.1)
				(type default)
			)
			(layer "F.Fab")
		)
		(fp_line
			(start -0.12065 0.2794)
			(end -0.12065 0.3048)
			(stroke
				(width 0.1)
				(type default)
			)
			(layer "F.Fab")
		)
		(fp_line
			(start 0.67945 0.3048)
			(end 0.120396 0.3048)
			(stroke
				(width 0.1)
				(type default)
			)
			(layer "F.Fab")
		)
		(fp_line
			(start 0.120396 0.3048)
			(end 0.120396 0.2794)
			(stroke
				(width 0.1)
				(type default)
			)
			(layer "F.Fab")
		)
		(fp_line
			(start -0.12065 0.3048)
			(end -0.67945 0.3048)
			(stroke
				(width 0.1)
				(type default)
			)
			(layer "F.Fab")
		)
		(fp_line
			(start -0.67945 0.3048)
			(end -0.67945 -0.305054)
			(stroke
				(width 0.1)
				(type default)
			)
			(layer "F.Fab")
		)
		(pad "1" smd circle
			(at -0.40005 0 90)
			(size 0 0)
			(layers "F.Cu" "F.Mask" "F.Paste")
			(net "PVDDCR_CPU1_P0_VCC")
		)
		(pad "2" smd circle
			(at 0.40005 0 90)
			(size 0 0)
			(layers "F.Cu" "F.Mask" "F.Paste")
			(net "GND")
		)
	)
	(footprint ""
		(layer "F.Cu")
		(at 315.813186 -361.279948)
		(property "Reference" "PC78"
			(at 0 0 0)
			(layer "F.SilkS")
			(hide yes)
			(effects
				(font
					(size 1.27 1.27)
				)
			)
		)
		(property "Value" ""
			(at 0 0 0)
			(layer "F.Fab")
			(effects
				(font
					(size 1.27 1.27)
				)
			)
		)
		(duplicate_pad_numbers_are_jumpers no)
		(fp_line
			(start -0.7874 -0.4064)
			(end 0.7874 -0.4064)
			(stroke
				(width 0.1524)
				(type default)
			)
			(layer "F.SilkS")
		)
		(fp_line
			(start -0.7874 0.4064)
			(end -0.7874 -0.4064)
			(stroke
				(width 0.1524)
				(type default)
			)
			(layer "F.SilkS")
		)
		(fp_line
			(start 0.7874 -0.4064)
			(end 0.7874 0.4064)
			(stroke
				(width 0.1524)
				(type default)
			)
			(layer "F.SilkS")
		)
		(fp_line
			(start 0.7874 0.4064)
			(end -0.7874 0.4064)
			(stroke
				(width 0.1524)
				(type default)
			)
			(layer "F.SilkS")
		)
		(fp_line
			(start -0.67945 -0.305054)
			(end -0.12065 -0.305054)
			(stroke
				(width 0.1)
				(type default)
			)
			(layer "F.Fab")
		)
		(fp_line
			(start -0.67945 0.3048)
			(end -0.67945 -0.305054)
			(stroke
				(width 0.1)
				(type default)
			)
			(layer "F.Fab")
		)
		(fp_line
			(start -0.12065 -0.305054)
			(end -0.12065 -0.2794)
			(stroke
				(width 0.1)
				(type default)
			)
			(layer "F.Fab")
		)
		(fp_line
			(start -0.12065 -0.2794)
			(end 0.12065 -0.2794)
			(stroke
				(width 0.1)
				(type default)
			)
			(layer "F.Fab")
		)
		(fp_line
			(start -0.12065 0.2794)
			(end -0.12065 0.3048)
			(stroke
				(width 0.1)
				(type default)
			)
			(layer "F.Fab")
		)
		(fp_line
			(start -0.12065 0.3048)
			(end -0.67945 0.3048)
			(stroke
				(width 0.1)
				(type default)
			)
			(layer "F.Fab")
		)
		(fp_line
			(start 0.120396 0.2794)
			(end -0.12065 0.2794)
			(stroke
				(width 0.1)
				(type default)
			)
			(layer "F.Fab")
		)
		(fp_line
			(start 0.120396 0.3048)
			(end 0.120396 0.2794)
			(stroke
				(width 0.1)
				(type default)
			)
			(layer "F.Fab")
		)
		(fp_line
			(start 0.12065 -0.3048)
			(end 0.67945 -0.3048)
			(stroke
				(width 0.1)
				(type default)
			)
			(layer "F.Fab")
		)
		(fp_line
			(start 0.12065 -0.2794)
			(end 0.12065 -0.3048)
			(stroke
				(width 0.1)
				(type default)
			)
			(layer "F.Fab")
		)
		(fp_line
			(start 0.67945 -0.3048)
			(end 0.67945 0.3048)
			(stroke
				(width 0.1)
				(type default)
			)
			(layer "F.Fab")
		)
		(fp_line
			(start 0.67945 0.3048)
			(end 0.120396 0.3048)
			(stroke
				(width 0.1)
				(type default)
			)
			(layer "F.Fab")
		)
		(pad "1" smd circle
			(at -0.40005 0)
			(size 0 0)
			(layers "F.Cu" "F.Mask" "F.Paste")
			(net "PVDDCR_CPU1_P0_TEMP0")
		)
		(pad "2" smd circle
			(at 0.40005 0)
			(size 0 0)
			(layers "F.Cu" "F.Mask" "F.Paste")
			(net "GND")
		)
	)
	(footprint ""
		(layer "F.Cu")
		(at 357.044244 -378.95403 -90)
		(property "Reference" "C939"
			(at 0 0 270)
			(layer "F.SilkS")
			(hide yes)
			(effects
				(font
					(size 1.27 1.27)
				)
			)
		)
		(property "Value" ""
			(at 0 0 270)
			(layer "F.Fab")
			(effects
				(font
					(size 1.27 1.27)
				)
			)
		)
		(duplicate_pad_numbers_are_jumpers no)
		(fp_line
			(start -0.299974 0.150114)
			(end -0.299974 -0.150114)
			(stroke
				(width 0.1)
				(type default)
			)
			(layer "F.Fab")
		)
		(fp_line
			(start 0.299974 0.150114)
			(end -0.299974 0.150114)
			(stroke
				(width 0.1)
				(type default)
			)
			(layer "F.Fab")
		)
		(fp_line
			(start -0.299974 -0.150114)
			(end 0.299974 -0.150114)
			(stroke
				(width 0.1)
				(type default)
			)
			(layer "F.Fab")
		)
		(fp_line
			(start 0.299974 -0.150114)
			(end 0.299974 0.150114)
			(stroke
				(width 0.1)
				(type default)
			)
			(layer "F.Fab")
		)
		(pad "1" smd rect
			(at -0.2667 0 270)
			(size 0.3048 0.381)
			(layers "F.Cu" "F.Mask" "F.Paste")
			(net "P5E_CPU0_P1_TX_C_DP<13>")
		)
		(pad "2" smd rect
			(at 0.2667 0 270)
			(size 0.3048 0.381)
			(layers "F.Cu" "F.Mask" "F.Paste")
			(net "P5E_CPU0_P1_TX_DP<13>")
		)
	)
	(footprint ""
		(layer "F.Cu")
		(at 342.923876 -70.098412 90)
		(property "Reference" "D83"
			(at -3.934714 -0.691642 90)
			(unlocked yes)
			(layer "F.SilkS")
			(effects
				(font
					(size 0.7874 0.5842)
					(thickness 0.1524)
				)
				(justify left)
			)
		)
		(property "Value" ""
			(at 0 0 90)
			(layer "F.Fab")
			(effects
				(font
					(size 1.27 1.27)
				)
			)
		)
		(duplicate_pad_numbers_are_jumpers no)
		(fp_line
			(start 1.16078 -0.4826)
			(end 1.16078 0.4826)
			(stroke
				(width 0.1524)
				(type default)
			)
			(layer "F.SilkS")
		)
		(fp_line
			(start 1.03378 -0.4826)
			(end 1.03378 0.4826)
			(stroke
				(width 0.1524)
				(type default)
			)
			(layer "F.SilkS")
		)
		(fp_line
			(start 0.90678 -0.4826)
			(end 0.90678 0.4826)
			(stroke
				(width 0.1524)
				(type default)
			)
			(layer "F.SilkS")
		)
		(fp_line
			(start -0.64008 -0.4826)
			(end 1.16078 -0.4826)
			(stroke
				(width 0.1524)
				(type default)
			)
			(layer "F.SilkS")
		)
		(fp_line
			(start -0.79248 -0.4826)
			(end 1.03378 -0.4826)
			(stroke
				(width 0.1524)
				(type default)
			)
			(layer "F.SilkS")
		)
		(fp_line
			(start -0.89408 -0.4826)
			(end 0.90678 -0.4826)
			(stroke
				(width 0.1524)
				(type default)
			)
			(layer "F.SilkS")
		)
		(fp_line
			(start 1.16078 0.4826)
			(end -0.64008 0.4826)
			(stroke
				(width 0.1524)
				(type default)
			)
			(layer "F.SilkS")
		)
		(fp_line
			(start 1.03378 0.4826)
			(end -0.79248 0.4826)
			(stroke
				(width 0.1524)
				(type default)
			)
			(layer "F.SilkS")
		)
		(fp_line
			(start 0.90678 0.4826)
			(end -0.90678 0.4826)
			(stroke
				(width 0.1524)
				(type default)
			)
			(layer "F.SilkS")
		)
		(fp_line
			(start -0.90678 0.4826)
			(end -0.90678 -0.4699)
			(stroke
				(width 0.1524)
				(type default)
			)
			(layer "F.SilkS")
		)
		(fp_line
			(start 0.499872 -0.249936)
			(end 0.499872 0.249936)
			(stroke
				(width 0.1)
				(type default)
			)
			(layer "F.Fab")
		)
		(fp_line
			(start -0.499872 -0.249936)
			(end 0.499872 -0.249936)
			(stroke
				(width 0.1)
				(type default)
			)
			(layer "F.Fab")
		)
		(fp_line
			(start 0.499872 0.249936)
			(end -0.499872 0.249936)
			(stroke
				(width 0.1)
				(type default)
			)
			(layer "F.Fab")
		)
		(fp_line
			(start -0.499872 0.249936)
			(end -0.499872 -0.249936)
			(stroke
				(width 0.1)
				(type default)
			)
			(layer "F.Fab")
		)
		(pad "A" smd rect
			(at -0.47498 0 90)
			(size 0.6096 0.7112)
			(layers "F.Cu" "F.Mask" "F.Paste")
			(net "LED_PWRGD_PVDDIO_P1_R")
		)
		(pad "C" smd rect
			(at 0.47498 0 90)
			(size 0.6096 0.7112)
			(layers "F.Cu" "F.Mask" "F.Paste")
			(net "LED_PWRGD_PVDDIO_P1_D")
		)
	)
	(footprint ""
		(layer "F.Cu")
		(at 332.070964 -140.008102 -90)
		(property "Reference" "PC113"
			(at 0 0 270)
			(layer "F.SilkS")
			(hide yes)
			(effects
				(font
					(size 1.27 1.27)
				)
			)
		)
		(property "Value" ""
			(at 0 0 270)
			(layer "F.Fab")
			(effects
				(font
					(size 1.27 1.27)
				)
			)
		)
		(duplicate_pad_numbers_are_jumpers no)
		(fp_line
			(start -0.7874 0.4064)
			(end -0.7874 -0.4064)
			(stroke
				(width 0.1524)
				(type default)
			)
			(layer "F.SilkS")
		)
		(fp_line
			(start 0.7874 0.4064)
			(end -0.7874 0.4064)
			(stroke
				(width 0.1524)
				(type default)
			)
			(layer "F.SilkS")
		)
		(fp_line
			(start -0.7874 -0.4064)
			(end 0.7874 -0.4064)
			(stroke
				(width 0.1524)
				(type default)
			)
			(layer "F.SilkS")
		)
		(fp_line
			(start 0.7874 -0.4064)
			(end 0.7874 0.4064)
			(stroke
				(width 0.1524)
				(type default)
			)
			(layer "F.SilkS")
		)
		(fp_line
			(start -0.67945 0.3048)
			(end -0.67945 -0.305054)
			(stroke
				(width 0.1)
				(type default)
			)
			(layer "F.Fab")
		)
		(fp_line
			(start -0.12065 0.3048)
			(end -0.67945 0.3048)
			(stroke
				(width 0.1)
				(type default)
			)
			(layer "F.Fab")
		)
		(fp_line
			(start 0.120396 0.3048)
			(end 0.120396 0.2794)
			(stroke
				(width 0.1)
				(type default)
			)
			(layer "F.Fab")
		)
		(fp_line
			(start 0.67945 0.3048)
			(end 0.120396 0.3048)
			(stroke
				(width 0.1)
				(type default)
			)
			(layer "F.Fab")
		)
		(fp_line
			(start -0.12065 0.2794)
			(end -0.12065 0.3048)
			(stroke
				(width 0.1)
				(type default)
			)
			(layer "F.Fab")
		)
		(fp_line
			(start 0.120396 0.2794)
			(end -0.12065 0.2794)
			(stroke
				(width 0.1)
				(type default)
			)
			(layer "F.Fab")
		)
		(fp_line
			(start -0.12065 -0.2794)
			(end 0.12065 -0.2794)
			(stroke
				(width 0.1)
				(type default)
			)
			(layer "F.Fab")
		)
		(fp_line
			(start 0.12065 -0.2794)
			(end 0.12065 -0.3048)
			(stroke
				(width 0.1)
				(type default)
			)
			(layer "F.Fab")
		)
		(fp_line
			(start 0.12065 -0.3048)
			(end 0.67945 -0.3048)
			(stroke
				(width 0.1)
				(type default)
			)
			(layer "F.Fab")
		)
		(fp_line
			(start 0.67945 -0.3048)
			(end 0.67945 0.3048)
			(stroke
				(width 0.1)
				(type default)
			)
			(layer "F.Fab")
		)
		(fp_line
			(start -0.67945 -0.305054)
			(end -0.12065 -0.305054)
			(stroke
				(width 0.1)
				(type default)
			)
			(layer "F.Fab")
		)
		(fp_line
			(start -0.12065 -0.305054)
			(end -0.12065 -0.2794)
			(stroke
				(width 0.1)
				(type default)
			)
			(layer "F.Fab")
		)
		(pad "1" smd circle
			(at -0.40005 0 270)
			(size 0 0)
			(layers "F.Cu" "F.Mask" "F.Paste")
			(net "PVDD18_S5_P0_REF")
		)
		(pad "2" smd circle
			(at 0.40005 0 270)
			(size 0 0)
			(layers "F.Cu" "F.Mask" "F.Paste")
			(net "PVDD18_S5_P0_RGND")
		)
	)
	(footprint ""
		(layer "F.Cu")
		(at 327.881742 -395.1732 90)
		(property "Reference" "R965"
			(at 0 0 90)
			(layer "F.SilkS")
			(hide yes)
			(effects
				(font
					(size 1.27 1.27)
				)
			)
		)
		(property "Value" ""
			(at 0 0 90)
			(layer "F.Fab")
			(effects
				(font
					(size 1.27 1.27)
				)
			)
		)
		(duplicate_pad_numbers_are_jumpers no)
		(fp_line
			(start 0.32512 -0.175006)
			(end 0.32512 0.175006)
			(stroke
				(width 0.1)
				(type default)
			)
			(layer "F.Fab")
		)
		(fp_line
			(start -0.32512 -0.175006)
			(end 0.32512 -0.175006)
			(stroke
				(width 0.1)
				(type default)
			)
			(layer "F.Fab")
		)
		(fp_line
			(start 0.32512 0.175006)
			(end -0.32512 0.175006)
			(stroke
				(width 0.1)
				(type default)
			)
			(layer "F.Fab")
		)
		(fp_line
			(start -0.32512 0.175006)
			(end -0.32512 -0.175006)
			(stroke
				(width 0.1)
				(type default)
			)
			(layer "F.Fab")
		)
		(pad "1" smd rect
			(at -0.2667 0 90)
			(size 0.3048 0.381)
			(layers "F.Cu" "F.Mask" "F.Paste")
			(net "RT_CPU0_P0_ADDR3")
		)
		(pad "2" smd rect
			(at 0.2667 0 270)
			(size 0.3048 0.381)
			(layers "F.Cu" "F.Mask" "F.Paste")
			(net "GND")
		)
	)
	(footprint ""
		(layer "F.Cu")
		(at 204.331824 -342.075262 -90.054)
		(property "Reference" "PR454"
			(at 0 0 269.946)
			(layer "F.SilkS")
			(hide yes)
			(effects
				(font
					(size 1.27 1.27)
				)
			)
		)
		(property "Value" ""
			(at 0 0 269.946)
			(layer "F.Fab")
			(effects
				(font
					(size 1.27 1.27)
				)
			)
		)
		(duplicate_pad_numbers_are_jumpers no)
		(fp_line
			(start 0.787275 0.40642)
			(end -0.787525 0.40638)
			(stroke
				(width 0.1524)
				(type default)
			)
			(layer "F.SilkS")
		)
		(fp_line
			(start -0.787525 0.40638)
			(end -0.787275 -0.40642)
			(stroke
				(width 0.1524)
				(type default)
			)
			(layer "F.SilkS")
		)
		(fp_line
			(start 0.787525 -0.40638)
			(end 0.787275 0.40642)
			(stroke
				(width 0.1524)
				(type default)
			)
			(layer "F.SilkS")
		)
		(fp_line
			(start -0.787275 -0.40642)
			(end 0.787525 -0.40638)
			(stroke
				(width 0.1524)
				(type default)
			)
			(layer "F.SilkS")
		)
		(fp_line
			(start 0.679484 0.304922)
			(end 0.120429 0.304687)
			(stroke
				(width 0.1)
				(type default)
			)
			(layer "F.Fab")
		)
		(fp_line
			(start -0.120617 0.304914)
			(end -0.679417 0.304678)
			(stroke
				(width 0.1)
				(type default)
			)
			(layer "F.Fab")
		)
		(fp_line
			(start 0.120429 0.304687)
			(end 0.120405 0.279287)
			(stroke
				(width 0.1)
				(type default)
			)
			(layer "F.Fab")
		)
		(fp_line
			(start -0.679417 0.304678)
			(end -0.679484 -0.305176)
			(stroke
				(width 0.1)
				(type default)
			)
			(layer "F.Fab")
		)
		(fp_line
			(start -0.120641 0.279514)
			(end -0.120617 0.304914)
			(stroke
				(width 0.1)
				(type default)
			)
			(layer "F.Fab")
		)
		(fp_line
			(start 0.120405 0.279287)
			(end -0.120641 0.279514)
			(stroke
				(width 0.1)
				(type default)
			)
			(layer "F.Fab")
		)
		(fp_line
			(start -0.120659 -0.279286)
			(end 0.120641 -0.279514)
			(stroke
				(width 0.1)
				(type default)
			)
			(layer "F.Fab")
		)
		(fp_line
			(start 0.120641 -0.279514)
			(end 0.120617 -0.304914)
			(stroke
				(width 0.1)
				(type default)
			)
			(layer "F.Fab")
		)
		(fp_line
			(start 0.679417 -0.304678)
			(end 0.679484 0.304922)
			(stroke
				(width 0.1)
				(type default)
			)
			(layer "F.Fab")
		)
		(fp_line
			(start 0.120617 -0.304914)
			(end 0.679417 -0.304678)
			(stroke
				(width 0.1)
				(type default)
			)
			(layer "F.Fab")
		)
		(fp_line
			(start -0.120683 -0.30494)
			(end -0.120659 -0.279286)
			(stroke
				(width 0.1)
				(type default)
			)
			(layer "F.Fab")
		)
		(fp_line
			(start -0.679484 -0.305176)
			(end -0.120683 -0.30494)
			(stroke
				(width 0.1)
				(type default)
			)
			(layer "F.Fab")
		)
		(pad "1" smd circle
			(at -0.40005 0 269.946)
			(size 0 0)
			(layers "F.Cu" "F.Mask" "F.Paste")
			(net "PVDD_33_S5_FB")
		)
		(pad "2" smd circle
			(at 0.40005 0 269.946)
			(size 0 0)
			(layers "F.Cu" "F.Mask" "F.Paste")
			(net "GND")
		)
	)
)
